(kicad_pcb
	(version 20240108)
	(generator "pcbnew")
	(generator_version "8.0")
	(general
		(thickness 1.62)
		(legacy_teardrops no)
	)
	(paper "A4")
	(title_block
		(title "Jetson Orin Baseboard")
		(date "2025-03-12")
		(rev "1.3.4")
		(company "Antmicro Ltd")
		(comment 1 "www.antmicro.com")
		(comment 9 "footprints 465-467 of 677")
	)
	(layers
		(0 "F.Cu" signal)
		(1 "In1.Cu" signal)
		(2 "In2.Cu" signal)
		(3 "In3.Cu" signal)
		(4 "In4.Cu" jumper)
		(5 "In5.Cu" signal)
		(6 "In6.Cu" signal)
		(31 "B.Cu" signal)
		(32 "B.Adhes" user "B.Adhesive")
		(33 "F.Adhes" user "F.Adhesive")
		(34 "B.Paste" user)
		(35 "F.Paste" user)
		(36 "B.SilkS" user "B.Silkscreen")
		(37 "F.SilkS" user "F.Silkscreen")
		(38 "B.Mask" user)
		(39 "F.Mask" user)
		(40 "Dwgs.User" user "User.Drawings")
		(41 "Cmts.User" user "User.Comments")
		(42 "Eco1.User" user "User.Eco1")
		(43 "Eco2.User" user "User.Eco2")
		(44 "Edge.Cuts" user)
		(45 "Margin" user)
		(46 "B.CrtYd" user "B.Courtyard")
		(47 "F.CrtYd" user "F.Courtyard")
		(48 "B.Fab" user)
		(49 "F.Fab" user)
	)
	(footprint "antmicro-footprints:Tag-Connect_TC2050-IDC-NL_2x5_P1.27mm"
		(layer "B.Cu")
		(at 83.909 125.2545 180)
		(property "Reference" "J9"
			(at 1.909 2.2245 0)
			(layer "B.SilkS")
			(effects
				(font
					(size 0.7 0.7)
					(thickness 0.15)
				)
				(justify left bottom mirror)
			)
		)
		(property "Value" "Tag-Connect_TC2050-IDC-NL_2x5_P1.27mm"
			(at 0 -4.4 0)
			(layer "B.Fab")
			(effects
				(font
					(size 0.7 0.7)
					(thickness 0.15)
				)
				(justify left bottom mirror)
			)
		)
		(property "Footprint" "antmicro-footprints:Tag-Connect_TC2050-IDC-NL_2x5_P1.27mm"
			(at 0 0 180)
			(layer "F.Fab")
			(hide yes)
			(effects
				(font
					(size 1.27 1.27)
					(thickness 0.15)
				)
			)
		)
		(property "Datasheet" "https://www.tag-connect.com/wp-content/uploads/bsk-pdf-manager/TC2050-IDC-NL_Datasheet_8.pdf"
			(at 0 0 180)
			(layer "F.Fab")
			(hide yes)
			(effects
				(font
					(size 1.27 1.27)
					(thickness 0.15)
				)
			)
		)
		(property "Author" "Antmicro"
			(at 167.818 250.509 0)
			(layer "B.Fab")
			(hide yes)
			(effects
				(font
					(size 1 1)
					(thickness 0.15)
				)
				(justify mirror)
			)
		)
		(property "License" "Apache-2.0"
			(at 167.818 250.509 0)
			(layer "B.Fab")
			(hide yes)
			(effects
				(font
					(size 1 1)
					(thickness 0.15)
				)
				(justify mirror)
			)
		)
		(property "MPN" "TC2050-IDC-NL"
			(at 167.818 250.509 0)
			(layer "B.Fab")
			(hide yes)
			(effects
				(font
					(size 1 1)
					(thickness 0.15)
				)
				(justify mirror)
			)
		)
		(property "Manufacturer" "Tag Connect"
			(at 167.818 250.509 0)
			(layer "B.Fab")
			(hide yes)
			(effects
				(font
					(size 1 1)
					(thickness 0.15)
				)
				(justify mirror)
			)
		)
		(sheetname "Peripherals")
		(sheetfile "peripherals.kicad_sch")
		(attr exclude_from_pos_files exclude_from_bom dnp)
		(fp_line
			(start 5.1 1.7)
			(end 4.7 2.05)
			(stroke
				(width 0.15)
				(type solid)
			)
			(layer "B.SilkS")
		)
		(fp_line
			(start 5.1 -1.7)
			(end 5.1 1.7)
			(stroke
				(width 0.15)
				(type solid)
			)
			(layer "B.SilkS")
		)
		(fp_line
			(start 5.1 -1.7)
			(end 4.7 -2.049)
			(stroke
				(width 0.15)
				(type solid)
			)
			(layer "B.SilkS")
		)
		(fp_line
			(start 4.7 2.05)
			(end -2.2 2.05)
			(stroke
				(width 0.15)
				(type solid)
			)
			(layer "B.SilkS")
		)
		(fp_line
			(start -2.2 2.05)
			(end -5.08 0.9)
			(stroke
				(width 0.15)
				(type solid)
			)
			(layer "B.SilkS")
		)
		(fp_line
			(start -2.3 -2.049)
			(end 4.7 -2.049)
			(stroke
				(width 0.15)
				(type solid)
			)
			(layer "B.SilkS")
		)
		(fp_line
			(start -3.101 -0.4)
			(end -3.101 -1.269)
			(stroke
				(width 0.15)
				(type solid)
			)
			(layer "B.SilkS")
		)
		(fp_line
			(start -5.08 0.9)
			(end -5.08 -0.8)
			(stroke
				(width 0.15)
				(type solid)
			)
			(layer "B.SilkS")
		)
		(fp_line
			(start -5.08 -0.8)
			(end -2.3 -2.049)
			(stroke
				(width 0.15)
				(type solid)
			)
			(layer "B.SilkS")
		)
		(fp_line
			(start 5.32 1.8)
			(end 4.8 2.3)
			(stroke
				(width 0.05)
				(type solid)
			)
			(layer "B.CrtYd")
		)
		(fp_line
			(start 5.32 -1.8)
			(end 5.32 1.8)
			(stroke
				(width 0.05)
				(type solid)
			)
			(layer "B.CrtYd")
		)
		(fp_line
			(start 5.32 -1.8)
			(end 4.8 -2.29)
			(stroke
				(width 0.05)
				(type solid)
			)
			(layer "B.CrtYd")
		)
		(fp_line
			(start 4.8 2.3)
			(end -2.3 2.3)
			(stroke
				(width 0.05)
				(type solid)
			)
			(layer "B.CrtYd")
		)
		(fp_line
			(start -2.3 2.3)
			(end -5.33 1.1)
			(stroke
				(width 0.05)
				(type solid)
			)
			(layer "B.CrtYd")
		)
		(fp_line
			(start -2.4 -2.29)
			(end 4.8 -2.29)
			(stroke
				(width 0.05)
				(type solid)
			)
			(layer "B.CrtYd")
		)
		(fp_line
			(start -5.33 1.1)
			(end -5.33 -1)
			(stroke
				(width 0.05)
				(type solid)
			)
			(layer "B.CrtYd")
		)
		(fp_line
			(start -5.33 -1)
			(end -2.4 -2.29)
			(stroke
				(width 0.05)
				(type solid)
			)
			(layer "B.CrtYd")
		)
		(fp_text user "License: Apache-2.0"
			(at -6.223 -8.449 0)
			(layer "B.Fab")
			(hide yes)
			(effects
				(font
					(size 0.7 0.7)
					(thickness 0.15)
				)
				(justify left bottom mirror)
			)
		)
		(fp_text user "${REFERENCE}"
			(at -6.223 -6.049 0)
			(layer "B.Fab")
			(hide yes)
			(effects
				(font
					(size 0.7 0.7)
					(thickness 0.15)
				)
				(justify left bottom mirror)
			)
		)
		(fp_text user "Author: Antmicro"
			(at -6.223 -7.249 0)
			(layer "B.Fab")
			(hide yes)
			(effects
				(font
					(size 0.7 0.7)
					(thickness 0.15)
				)
				(justify left bottom mirror)
			)
		)
		(pad "" np_thru_hole circle
			(at -3.81 0 180)
			(size 0.9906 0.9906)
			(drill 0.9906)
			(layers "*.Cu" "*.Mask")
		)
		(pad "" np_thru_hole circle
			(at 3.809 -1.015 180)
			(size 0.9906 0.9906)
			(drill 0.9906)
			(layers "*.Cu" "*.Mask")
		)
		(pad "" np_thru_hole circle
			(at 3.809 1.016 180)
			(size 0.9906 0.9906)
			(drill 0.9906)
			(layers "*.Cu" "*.Mask")
		)
		(pad "1" connect circle
			(at -2.54 -0.634 180)
			(size 0.7874 0.7874)
			(layers "B.Cu" "B.Mask")
			(net 98 "EEPROM_PWR")
			(pinfunction "3V3")
			(pintype "passive")
		)
		(pad "2" connect circle
			(at -1.27 -0.634 180)
			(size 0.7874 0.7874)
			(layers "B.Cu" "B.Mask")
			(net 772 "/Peripherals/~{CS}")
			(pinfunction "SPI_CS")
			(pintype "passive")
		)
		(pad "3" connect circle
			(at 0 -0.634 180)
			(size 0.7874 0.7874)
			(layers "B.Cu" "B.Mask")
			(net 1 "GND")
			(pinfunction "GND")
			(pintype "passive")
		)
		(pad "4" connect circle
			(at 1.269 -0.634 180)
			(size 0.7874 0.7874)
			(layers "B.Cu" "B.Mask")
			(net 671 "/Peripherals/SCK")
			(pinfunction "SPI_SCK")
			(pintype "passive")
		)
		(pad "5" connect circle
			(at 2.539 -0.634 180)
			(size 0.7874 0.7874)
			(layers "B.Cu" "B.Mask")
			(net 1 "GND")
			(pinfunction "GND")
			(pintype "passive")
		)
		(pad "6" connect circle
			(at 2.539 0.635 180)
			(size 0.7874 0.7874)
			(layers "B.Cu" "B.Mask")
			(net 773 "/Peripherals/MISO")
			(pinfunction "SPI_MISO")
			(pintype "passive")
		)
		(pad "7" connect circle
			(at 1.269 0.635 180)
			(size 0.7874 0.7874)
			(layers "B.Cu" "B.Mask")
			(net 775 "unconnected-(J9-Pad7)")
			(pinfunction "NC")
			(pintype "passive+no_connect")
		)
		(pad "8" connect circle
			(at 0 0.635 180)
			(size 0.7874 0.7874)
			(layers "B.Cu" "B.Mask")
			(net 774 "/Peripherals/MOSI")
			(pinfunction "SPI_MOSI")
			(pintype "passive")
		)
		(pad "9" connect circle
			(at -1.27 0.635 180)
			(size 0.7874 0.7874)
			(layers "B.Cu" "B.Mask")
			(net 1 "GND")
			(pinfunction "GND")
			(pintype "passive")
		)
		(pad "10" connect circle
			(at -2.54 0.635 180)
			(size 0.7874 0.7874)
			(layers "B.Cu" "B.Mask")
			(net 776 "unconnected-(J9-Pad10)")
			(pinfunction "SPI_NC")
			(pintype "passive+no_connect")
		)
	)
	(footprint "antmicro-footprints:SOD-923"
		(layer "B.Cu")
		(at 69.8 81 -90)
		(property "Reference" "D30"
			(at -0.83 0.56 90)
			(unlocked yes)
			(layer "B.SilkS")
			(effects
				(font
					(size 0.7 0.7)
					(thickness 0.15)
				)
				(justify left bottom mirror)
			)
		)
		(property "Value" "ESD9X5.0ST5G"
			(at 0 -1.3 90)
			(unlocked yes)
			(layer "B.Fab")
			(effects
				(font
					(size 0.7 0.7)
					(thickness 0.15)
				)
				(justify left bottom mirror)
			)
		)
		(property "Footprint" "antmicro-footprints:SOD-923"
			(at 0 0 -90)
			(layer "F.Fab")
			(hide yes)
			(effects
				(font
					(size 1.27 1.27)
					(thickness 0.15)
				)
			)
		)
		(property "Datasheet" "https://www.onsemi.com/pdf/datasheet/esd9x3.3st5g-d.pdf"
			(at 0 0 -90)
			(layer "F.Fab")
			(hide yes)
			(effects
				(font
					(size 1.27 1.27)
					(thickness 0.15)
				)
			)
		)
		(property "Author" "Antmicro"
			(at -11.2 150.8 0)
			(layer "B.Fab")
			(hide yes)
			(effects
				(font
					(size 1 1)
					(thickness 0.15)
				)
				(justify mirror)
			)
		)
		(property "License" "Apache-2.0"
			(at -11.2 150.8 0)
			(layer "B.Fab")
			(hide yes)
			(effects
				(font
					(size 1 1)
					(thickness 0.15)
				)
				(justify mirror)
			)
		)
		(property "MPN" "ESD9X5.0ST5G"
			(at -11.2 150.8 0)
			(layer "B.Fab")
			(hide yes)
			(effects
				(font
					(size 1 1)
					(thickness 0.15)
				)
				(justify mirror)
			)
		)
		(property "Manufacturer" "ON Semiconductor"
			(at -11.2 150.8 0)
			(layer "B.Fab")
			(hide yes)
			(effects
				(font
					(size 1 1)
					(thickness 0.15)
				)
				(justify mirror)
			)
		)
		(sheetname "Supply")
		(sheetfile "supply.kicad_sch")
		(attr smd)
		(fp_line
			(start -0.5 0.4)
			(end -0.5 0.3)
			(stroke
				(width 0.15)
				(type solid)
			)
			(layer "B.SilkS")
		)
		(fp_line
			(start 0.5 0.4)
			(end -0.5 0.4)
			(stroke
				(width 0.15)
				(type solid)
			)
			(layer "B.SilkS")
		)
		(fp_line
			(start 0.5 0.3)
			(end 0.5 0.4)
			(stroke
				(width 0.15)
				(type solid)
			)
			(layer "B.SilkS")
		)
		(fp_line
			(start -0.5 -0.3)
			(end -0.5 -0.4)
			(stroke
				(width 0.15)
				(type solid)
			)
			(layer "B.SilkS")
		)
		(fp_line
			(start 0.5 -0.3)
			(end 0.5 -0.4)
			(stroke
				(width 0.15)
				(type solid)
			)
			(layer "B.SilkS")
		)
		(fp_line
			(start -0.16 -0.4)
			(end -0.16 0.4)
			(stroke
				(width 0.15)
				(type solid)
			)
			(layer "B.SilkS")
		)
		(fp_line
			(start 0.5 -0.4)
			(end -0.5 -0.4)
			(stroke
				(width 0.15)
				(type solid)
			)
			(layer "B.SilkS")
		)
		(fp_rect
			(start -0.68 0.41)
			(end 0.68 -0.41)
			(stroke
				(width 0.05)
				(type solid)
			)
			(fill none)
			(layer "B.CrtYd")
		)
		(fp_line
			(start -0.202 -0.298)
			(end -0.202 0.3)
			(stroke
				(width 0.15)
				(type solid)
			)
			(layer "B.Fab")
		)
		(fp_rect
			(start -0.402 0.3)
			(end 0.4 -0.298)
			(stroke
				(width 0.15)
				(type solid)
			)
			(fill none)
			(layer "B.Fab")
		)
		(fp_text user "${REFERENCE}"
			(at -0.68 -3.3 90)
			(unlocked yes)
			(layer "B.Fab")
			(hide yes)
			(effects
				(font
					(size 0.7 0.7)
					(thickness 0.15)
				)
				(justify left bottom mirror)
			)
		)
		(fp_text user "License: Apache-2.0"
			(at -0.68 -4.5 90)
			(layer "B.Fab")
			(hide yes)
			(effects
				(font
					(size 0.7 0.7)
					(thickness 0.15)
				)
				(justify left bottom mirror)
			)
		)
		(fp_text user "Author: Antmicro"
			(at -0.68 -5.7 90)
			(layer "B.Fab")
			(hide yes)
			(effects
				(font
					(size 0.7 0.7)
					(thickness 0.15)
				)
				(justify left bottom mirror)
			)
		)
		(pad "1" smd roundrect
			(at -0.438 0 270)
			(size 0.4 0.325)
			(layers "B.Cu" "B.Paste" "B.Mask")
			(roundrect_rratio 0.25)
			(net 117 "3V3_STDB")
			(pinfunction "C")
			(pintype "passive")
		)
		(pad "2" smd roundrect
			(at 0.436 0 270)
			(size 0.4 0.325)
			(layers "B.Cu" "B.Paste" "B.Mask")
			(roundrect_rratio 0.25)
			(net 1 "GND")
			(pinfunction "A")
			(pintype "passive")
		)
	)
	(footprint "antmicro-footprints:R_0402_1005Metric"
		(layer "B.Cu")
		(at 63.84 98.6)
		(descr "Resistor SMD 0402")
		(tags "resistor SMD 0402")
		(property "Reference" "R65"
			(at 3.95 -1.72 180)
			(layer "B.SilkS")
			(effects
				(font
					(size 0.7 0.7)
					(thickness 0.15)
				)
				(justify left bottom mirror)
			)
		)
		(property "Value" "R_0R_0402"
			(at 0 -1.4 180)
			(layer "B.Fab")
			(effects
				(font
					(size 0.7 0.7)
					(thickness 0.15)
				)
				(justify left bottom mirror)
			)
		)
		(property "Footprint" "antmicro-footprints:R_0402_1005Metric"
			(at 0 0 0)
			(layer "F.Fab")
			(hide yes)
			(effects
				(font
					(size 1.27 1.27)
					(thickness 0.15)
				)
			)
		)
		(property "Datasheet" "https://industrial.panasonic.com/cdbs/www-data/pdf/RDA0000/AOA0000C301.pdf"
			(at 0 0 0)
			(layer "F.Fab")
			(hide yes)
			(effects
				(font
					(size 1.27 1.27)
					(thickness 0.15)
				)
			)
		)
		(property "Author" "Antmicro"
			(at 0 0 0)
			(layer "B.Fab")
			(hide yes)
			(effects
				(font
					(size 1 1)
					(thickness 0.15)
				)
				(justify mirror)
			)
		)
		(property "Current" "1A"
			(at 0 0 0)
			(layer "B.Fab")
			(hide yes)
			(effects
				(font
					(size 1 1)
					(thickness 0.15)
				)
				(justify mirror)
			)
		)
		(property "License" "Apache-2.0"
			(at 0 0 0)
			(layer "B.Fab")
			(hide yes)
			(effects
				(font
					(size 1 1)
					(thickness 0.15)
				)
				(justify mirror)
			)
		)
		(property "MPN" "ERJ2GE0R00X"
			(at 0 0 0)
			(layer "B.Fab")
			(hide yes)
			(effects
				(font
					(size 1 1)
					(thickness 0.15)
				)
				(justify mirror)
			)
		)
		(property "Manufacturer" "Panasonic"
			(at 0 0 0)
			(layer "B.Fab")
			(hide yes)
			(effects
				(font
					(size 1 1)
					(thickness 0.15)
				)
				(justify mirror)
			)
		)
		(property "Tolerance" ""
			(at 0 0 0)
			(layer "B.Fab")
			(hide yes)
			(effects
				(font
					(size 1 1)
					(thickness 0.15)
				)
				(justify mirror)
			)
		)
		(property "Val" "0R"
			(at 0 0 0)
			(layer "B.Fab")
			(hide yes)
			(effects
				(font
					(size 1 1)
					(thickness 0.15)
				)
				(justify mirror)
			)
		)
		(sheetname "USB Debug, DP")
		(sheetfile "usb.kicad_sch")
		(attr smd)
		(fp_rect
			(start -0.925 0.47)
			(end 0.925 -0.47)
			(stroke
				(width 0.05)
				(type default)
			)
			(fill none)
			(layer "B.CrtYd")
		)
		(fp_rect
			(start -0.5 0.25)
			(end 0.5 -0.25)
			(stroke
				(width 0.15)
				(type solid)
			)
			(fill none)
			(layer "B.Fab")
		)
		(fp_text user "${REFERENCE}"
			(at -0.95 -3.168 180)
			(layer "B.Fab")
			(hide yes)
			(effects
				(font
					(size 0.7 0.7)
					(thickness 0.15)
				)
				(justify left bottom mirror)
			)
		)
		(fp_text user "License: Apache-2.0"
			(at -0.95 -5.169 180)
			(layer "B.Fab")
			(hide yes)
			(effects
				(font
					(size 0.7 0.7)
					(thickness 0.15)
				)
				(justify left bottom mirror)
			)
		)
		(fp_text user "Author: Antmicro"
			(at -0.95 -4.169 180)
			(layer "B.Fab")
			(hide yes)
			(effects
				(font
					(size 0.7 0.7)
					(thickness 0.15)
				)
				(justify left bottom mirror)
			)
		)
		(pad "1" smd roundrect
			(at -0.48 0)
			(size 0.59 0.64)
			(layers "B.Cu" "B.Paste" "B.Mask")
			(roundrect_rratio 0.25)
			(net 677 "USBC_HPD")
			(pintype "passive")
		)
		(pad "2" smd roundrect
			(at 0.48 0)
			(size 0.59 0.64)
			(layers "B.Cu" "B.Paste" "B.Mask")
			(roundrect_rratio 0.25)
			(net 670 "/USB Debug, DP/PDC_HPD2")
			(pintype "passive")
		)
	)
)
